FILE_TYPE = MACRO_DRAWING;
SET COLOR_WIRE YELLOW;
SET COLOR_PROP ORANGE;
SET COLOR_DOT WHITE;
SET COLOR_ARC YELLOW;
SET COLOR_BODY GREEN;
SET COLOR_NOTE PURPLE;
SET PROP_DISPLAY VALUE;
SET PAGE_NUMBER P416;
FORCEADD PT5161LRS..6
(-7750 4400);
FORCEPROP 1 LAST LOCATION U6012
J 0
(-8100 6025);
DISPLAY 0.723404 (-8100 6025);
PAINT GREEN (-8100 6025);
FORCEPROP 0 LAST $SEC 6
J 0
(-8100 6175);
DISPLAY 0.680851 (-8100 6175);
PAINT MONO (-8100 6175);
DISPLAY INVISIBLE (-8100 6175);
FORCEPROP 0 LAST CDS_SEC 6
J 0
(-8100 6175);
DISPLAY 0.680851 (-8100 6175);
DISPLAY INVISIBLE (-8100 6175);
FORCEPROP 0 LASTPIN (-7300 5550) $PN P29
J 0
(-7290 5560);
DISPLAY 0.680851 (-7290 5560);
PAINT MONO (-7290 5560);
FORCEPROP 0 LASTPIN (-7300 5200) $PN AA29
J 0
(-7290 5210);
DISPLAY 0.680851 (-7290 5210);
PAINT MONO (-7290 5210);
FORCEPROP 0 LASTPIN (-7300 4850) $PN AH29
J 0
(-7290 4860);
DISPLAY 0.680851 (-7290 4860);
PAINT MONO (-7290 4860);
FORCEPROP 0 LASTPIN (-7300 4500) $PN AR29
J 0
(-7290 4510);
DISPLAY 0.680851 (-7290 4510);
PAINT MONO (-7290 4510);
FORCEPROP 0 LASTPIN (-7300 4150) $PN BB29
J 0
(-7290 4160);
DISPLAY 0.680851 (-7290 4160);
PAINT MONO (-7290 4160);
FORCEPROP 0 LASTPIN (-7300 3800) $PN BJ29
J 0
(-7290 3810);
DISPLAY 0.680851 (-7290 3810);
PAINT MONO (-7290 3810);
FORCEPROP 0 LASTPIN (-7300 3450) $PN BT29
J 0
(-7290 3460);
DISPLAY 0.680851 (-7290 3460);
PAINT MONO (-7290 3460);
FORCEPROP 0 LASTPIN (-7300 3100) $PN CC29
J 0
(-7290 3110);
DISPLAY 0.680851 (-7290 3110);
PAINT MONO (-7290 3110);
FORCEPROP 0 LASTPIN (-7300 5650) $PN M26
J 0
(-7290 5660);
DISPLAY 0.680851 (-7290 5660);
PAINT MONO (-7290 5660);
FORCEPROP 0 LASTPIN (-7300 5300) $PN W26
J 0
(-7290 5310);
DISPLAY 0.680851 (-7290 5310);
PAINT MONO (-7290 5310);
FORCEPROP 0 LASTPIN (-7300 4950) $PN AF26
J 0
(-7290 4960);
DISPLAY 0.680851 (-7290 4960);
PAINT MONO (-7290 4960);
FORCEPROP 0 LASTPIN (-7300 4600) $PN AN26
J 0
(-7290 4610);
DISPLAY 0.680851 (-7290 4610);
PAINT MONO (-7290 4610);
FORCEPROP 0 LASTPIN (-7300 4250) $PN AY26
J 0
(-7290 4260);
DISPLAY 0.680851 (-7290 4260);
PAINT MONO (-7290 4260);
FORCEPROP 0 LASTPIN (-7300 3900) $PN BG26
J 0
(-7290 3910);
DISPLAY 0.680851 (-7290 3910);
PAINT MONO (-7290 3910);
FORCEPROP 0 LASTPIN (-7300 3550) $PN BP26
J 0
(-7290 3560);
DISPLAY 0.680851 (-7290 3560);
PAINT MONO (-7290 3560);
FORCEPROP 0 LASTPIN (-7300 3200) $PN CA26
J 0
(-7290 3210);
DISPLAY 0.680851 (-7290 3210);
PAINT MONO (-7290 3210);
FORCEPROP 2 LAST VALUE PT5161LRS
J 0
(-8100 6075);
DISPLAY 0.680851 (-8100 6075);
FORCEPROP 2 LAST PART_TYPE SMLF
J 0
(-8100 6125);
DISPLAY 0.680851 (-8100 6125);
FORCEPROP 1 LAST MATERIAL IC
J 0
(-8100 5875);
DISPLAY 0.723404 (-8100 5875);
PAINT GREEN (-8100 5875);
FORCEPROP 1 LAST NEEDS_NO_SIZE TRUE
J 0
(-7750 4400);
DISPLAY 0.723404 (-7750 4400);
PAINT GREEN (-7750 4400);
DISPLAY INVISIBLE (-7750 4400);
FORCEPROP 1 LAST CDS_LMAN_SYM_OUTLINE -350,1450,300,-1400
J 0
(-7750 4400);
DISPLAY 0.468085 (-7750 4400);
PAINT GREEN (-7750 4400);
DISPLAY INVISIBLE (-7750 4400);
FORCEPROP 2 LAST CDS_LIB pure_quanta
J 0
(-7750 4400);
DISPLAY INVISIBLE (-7750 4400);
FORCEPROP 1 LAST PATH I1
J 0
(-7750 4400);
DISPLAY 0.723404 (-7750 4400);
PAINT GREEN (-7750 4400);
DISPLAY INVISIBLE (-7750 4400);
FORCEPROP 1 LAST PART_NUMBER AJ051610U03
J 0
(-8100 5950);
DISPLAY 0.723404 (-8100 5950);
PAINT GREEN (-8100 5950);
DISPLAY INVISIBLE (-8100 5950);
FORCEADD TAP..1
(-6525 4150);
FORCEPROP 3 LASTPIN (-6575 4150) SIG_NAME P5E_CPU0_P2_RX_DN<11>
J 0
(-6565 4160);
DISPLAY 0.659574 (-6565 4160);
PAINT MONO (-6565 4160);
DISPLAY INVISIBLE (-6565 4160);
FORCEPROP 1 LASTPIN (-6575 4150) BN 11
J 0
(-6587 4158);
DISPLAY 0.680851 (-6587 4158);
PAINT GREEN (-6587 4158);
FORCEPROP 2 LAST CDS_LIB standard
J 0
(-6525 4150);
DISPLAY INVISIBLE (-6525 4150);
FORCEPROP 1 LAST BODY_TYPE PLUMBING
J 0
(-6525 4200);
DISPLAY 0.872340 (-6525 4200);
PAINT GREEN (-6525 4200);
DISPLAY INVISIBLE (-6525 4200);
FORCEPROP 1 LAST HDL_TAP TRUE
J 0
(-6200 4025);
DISPLAY 0.872340 (-6200 4025);
DISPLAY INVISIBLE (-6200 4025);
FORCEPROP 1 LAST PATH I10
J 0
(-6527 4150);
DISPLAY 0.872340 (-6527 4150);
PAINT GREEN (-6527 4150);
DISPLAY INVISIBLE (-6527 4150);
FORCEADD TAP..1
(-6525 4500);
FORCEPROP 3 LASTPIN (-6575 4500) SIG_NAME P5E_CPU0_P2_RX_DN<12>
J 0
(-6565 4510);
DISPLAY 0.659574 (-6565 4510);
PAINT MONO (-6565 4510);
DISPLAY INVISIBLE (-6565 4510);
FORCEPROP 1 LASTPIN (-6575 4500) BN 12
J 0
(-6587 4508);
DISPLAY 0.680851 (-6587 4508);
PAINT GREEN (-6587 4508);
FORCEPROP 2 LAST CDS_LIB standard
J 0
(-6525 4500);
DISPLAY INVISIBLE (-6525 4500);
FORCEPROP 1 LAST BODY_TYPE PLUMBING
J 0
(-6525 4550);
DISPLAY 0.872340 (-6525 4550);
PAINT GREEN (-6525 4550);
DISPLAY INVISIBLE (-6525 4550);
FORCEPROP 1 LAST HDL_TAP TRUE
J 0
(-6200 4375);
DISPLAY 0.872340 (-6200 4375);
DISPLAY INVISIBLE (-6200 4375);
FORCEPROP 1 LAST PATH I11
J 0
(-6527 4500);
DISPLAY 0.872340 (-6527 4500);
PAINT GREEN (-6527 4500);
DISPLAY INVISIBLE (-6527 4500);
FORCEADD TAP..1
(-6725 4950);
FORCEPROP 3 LASTPIN (-6775 4950) SIG_NAME P5E_CPU0_P2_RX_DP<13>
J 0
(-6765 4960);
DISPLAY 0.659574 (-6765 4960);
PAINT MONO (-6765 4960);
DISPLAY INVISIBLE (-6765 4960);
FORCEPROP 1 LASTPIN (-6775 4950) BN 13
J 0
(-6787 4958);
DISPLAY 0.680851 (-6787 4958);
PAINT GREEN (-6787 4958);
FORCEPROP 2 LAST CDS_LIB standard
J 0
(-6725 4950);
DISPLAY INVISIBLE (-6725 4950);
FORCEPROP 1 LAST BODY_TYPE PLUMBING
J 0
(-6725 5000);
DISPLAY 0.872340 (-6725 5000);
PAINT GREEN (-6725 5000);
DISPLAY INVISIBLE (-6725 5000);
FORCEPROP 1 LAST HDL_TAP TRUE
J 0
(-6400 4825);
DISPLAY 0.872340 (-6400 4825);
DISPLAY INVISIBLE (-6400 4825);
FORCEPROP 1 LAST PATH I12
J 0
(-6727 4950);
DISPLAY 0.872340 (-6727 4950);
PAINT GREEN (-6727 4950);
DISPLAY INVISIBLE (-6727 4950);
FORCEADD TAP..1
(-6725 5300);
FORCEPROP 3 LASTPIN (-6775 5300) SIG_NAME P5E_CPU0_P2_RX_DP<14>
J 0
(-6765 5310);
DISPLAY 0.659574 (-6765 5310);
PAINT MONO (-6765 5310);
DISPLAY INVISIBLE (-6765 5310);
FORCEPROP 1 LASTPIN (-6775 5300) BN 14
J 0
(-6787 5308);
DISPLAY 0.680851 (-6787 5308);
PAINT GREEN (-6787 5308);
FORCEPROP 2 LAST CDS_LIB standard
J 0
(-6725 5300);
DISPLAY INVISIBLE (-6725 5300);
FORCEPROP 1 LAST BODY_TYPE PLUMBING
J 0
(-6725 5350);
DISPLAY 0.872340 (-6725 5350);
PAINT GREEN (-6725 5350);
DISPLAY INVISIBLE (-6725 5350);
FORCEPROP 1 LAST HDL_TAP TRUE
J 0
(-6400 5175);
DISPLAY 0.872340 (-6400 5175);
DISPLAY INVISIBLE (-6400 5175);
FORCEPROP 1 LAST PATH I13
J 0
(-6727 5300);
DISPLAY 0.872340 (-6727 5300);
PAINT GREEN (-6727 5300);
DISPLAY INVISIBLE (-6727 5300);
FORCEADD TAP..1
(-6725 5650);
FORCEPROP 3 LASTPIN (-6775 5650) SIG_NAME P5E_CPU0_P2_RX_DP<15>
J 0
(-6765 5660);
DISPLAY 0.659574 (-6765 5660);
PAINT MONO (-6765 5660);
DISPLAY INVISIBLE (-6765 5660);
FORCEPROP 1 LASTPIN (-6775 5650) BN 15
J 0
(-6787 5658);
DISPLAY 0.680851 (-6787 5658);
PAINT GREEN (-6787 5658);
FORCEPROP 2 LAST CDS_LIB standard
J 0
(-6725 5650);
DISPLAY INVISIBLE (-6725 5650);
FORCEPROP 1 LAST BODY_TYPE PLUMBING
J 0
(-6725 5700);
DISPLAY 0.872340 (-6725 5700);
PAINT GREEN (-6725 5700);
DISPLAY INVISIBLE (-6725 5700);
FORCEPROP 1 LAST HDL_TAP TRUE
J 0
(-6400 5525);
DISPLAY 0.872340 (-6400 5525);
DISPLAY INVISIBLE (-6400 5525);
FORCEPROP 1 LAST PATH I14
J 0
(-6727 5650);
DISPLAY 0.872340 (-6727 5650);
PAINT GREEN (-6727 5650);
DISPLAY INVISIBLE (-6727 5650);
FORCEADD TAP..1
(-6525 4850);
FORCEPROP 3 LASTPIN (-6575 4850) SIG_NAME P5E_CPU0_P2_RX_DN<13>
J 0
(-6565 4860);
DISPLAY 0.659574 (-6565 4860);
PAINT MONO (-6565 4860);
DISPLAY INVISIBLE (-6565 4860);
FORCEPROP 1 LASTPIN (-6575 4850) BN 13
J 0
(-6587 4858);
DISPLAY 0.680851 (-6587 4858);
PAINT GREEN (-6587 4858);
FORCEPROP 2 LAST CDS_LIB standard
J 0
(-6525 4850);
DISPLAY INVISIBLE (-6525 4850);
FORCEPROP 1 LAST BODY_TYPE PLUMBING
J 0
(-6525 4900);
DISPLAY 0.872340 (-6525 4900);
PAINT GREEN (-6525 4900);
DISPLAY INVISIBLE (-6525 4900);
FORCEPROP 1 LAST HDL_TAP TRUE
J 0
(-6200 4725);
DISPLAY 0.872340 (-6200 4725);
DISPLAY INVISIBLE (-6200 4725);
FORCEPROP 1 LAST PATH I15
J 0
(-6527 4850);
DISPLAY 0.872340 (-6527 4850);
PAINT GREEN (-6527 4850);
DISPLAY INVISIBLE (-6527 4850);
FORCEADD TAP..1
(-6525 5200);
FORCEPROP 3 LASTPIN (-6575 5200) SIG_NAME P5E_CPU0_P2_RX_DN<14>
J 0
(-6565 5210);
DISPLAY 0.659574 (-6565 5210);
PAINT MONO (-6565 5210);
DISPLAY INVISIBLE (-6565 5210);
FORCEPROP 1 LASTPIN (-6575 5200) BN 14
J 0
(-6587 5208);
DISPLAY 0.680851 (-6587 5208);
PAINT GREEN (-6587 5208);
FORCEPROP 2 LAST CDS_LIB standard
J 0
(-6525 5200);
DISPLAY INVISIBLE (-6525 5200);
FORCEPROP 1 LAST BODY_TYPE PLUMBING
J 0
(-6525 5250);
DISPLAY 0.872340 (-6525 5250);
PAINT GREEN (-6525 5250);
DISPLAY INVISIBLE (-6525 5250);
FORCEPROP 1 LAST HDL_TAP TRUE
J 0
(-6200 5075);
DISPLAY 0.872340 (-6200 5075);
DISPLAY INVISIBLE (-6200 5075);
FORCEPROP 1 LAST PATH I16
J 0
(-6527 5200);
DISPLAY 0.872340 (-6527 5200);
PAINT GREEN (-6527 5200);
DISPLAY INVISIBLE (-6527 5200);
FORCEADD TAP..1
(-6525 5550);
FORCEPROP 3 LASTPIN (-6575 5550) SIG_NAME P5E_CPU0_P2_RX_DN<15>
J 0
(-6565 5560);
DISPLAY 0.659574 (-6565 5560);
PAINT MONO (-6565 5560);
DISPLAY INVISIBLE (-6565 5560);
FORCEPROP 1 LASTPIN (-6575 5550) BN 15
J 0
(-6587 5558);
DISPLAY 0.680851 (-6587 5558);
PAINT GREEN (-6587 5558);
FORCEPROP 2 LAST CDS_LIB standard
J 0
(-6525 5550);
DISPLAY INVISIBLE (-6525 5550);
FORCEPROP 1 LAST BODY_TYPE PLUMBING
J 0
(-6525 5600);
DISPLAY 0.872340 (-6525 5600);
PAINT GREEN (-6525 5600);
DISPLAY INVISIBLE (-6525 5600);
FORCEPROP 1 LAST HDL_TAP TRUE
J 0
(-6200 5425);
DISPLAY 0.872340 (-6200 5425);
DISPLAY INVISIBLE (-6200 5425);
FORCEPROP 1 LAST PATH I17
J 0
(-6527 5550);
DISPLAY 0.872340 (-6527 5550);
PAINT GREEN (-6527 5550);
DISPLAY INVISIBLE (-6527 5550);
FORCEADD OFFPAGE..5
R 2
(-5525 5800);
FORCEPROP 2 LAST $XR0 25 
J 0
(-5336 5800);
DISPLAY 0.638298 (-5336 5800);
PAINT MONO (-5336 5800);
FORCEPROP 2 LAST CDS_LIB standard
J 0
(-5525 5800);
DISPLAY INVISIBLE (-5525 5800);
FORCEPROP 1 LAST OFFPAGE TRUE
J 2
(-5850 5675);
DISPLAY 0.872340 (-5850 5675);
PAINT GREEN (-5850 5675);
DISPLAY INVISIBLE (-5850 5675);
FORCEPROP 1 LAST COMMENT_BODY TRUE
J 2
(-5625 5725);
DISPLAY 0.872340 (-5625 5725);
PAINT GREEN (-5625 5725);
DISPLAY INVISIBLE (-5625 5725);
FORCEPROP 2 LAST PATH I18
J 0
(-5350 5875);
DISPLAY 0.680851 (-5350 5875);
DISPLAY INVISIBLE (-5350 5875);
FORCEADD OFFPAGE..5
R 2
(-5500 5900);
FORCEPROP 2 LAST $XR0 25 
J 0
(-5311 5900);
DISPLAY 0.638298 (-5311 5900);
PAINT MONO (-5311 5900);
FORCEPROP 2 LAST CDS_LIB standard
J 0
(-5500 5900);
DISPLAY INVISIBLE (-5500 5900);
FORCEPROP 1 LAST OFFPAGE TRUE
J 2
(-5825 5775);
DISPLAY 0.872340 (-5825 5775);
PAINT GREEN (-5825 5775);
DISPLAY INVISIBLE (-5825 5775);
FORCEPROP 1 LAST COMMENT_BODY TRUE
J 2
(-5600 5825);
DISPLAY 0.872340 (-5600 5825);
PAINT GREEN (-5600 5825);
DISPLAY INVISIBLE (-5600 5825);
FORCEPROP 2 LAST PATH I19
J 0
(-5325 5975);
DISPLAY 0.680851 (-5325 5975);
DISPLAY INVISIBLE (-5325 5975);
FORCEADD TAP..1
(-6725 3200);
FORCEPROP 3 LASTPIN (-6775 3200) SIG_NAME P5E_CPU0_P2_RX_DP<8>
J 0
(-6765 3210);
DISPLAY 0.659574 (-6765 3210);
PAINT MONO (-6765 3210);
DISPLAY INVISIBLE (-6765 3210);
FORCEPROP 1 LASTPIN (-6775 3200) BN 8
J 0
(-6787 3208);
DISPLAY 0.680851 (-6787 3208);
PAINT GREEN (-6787 3208);
FORCEPROP 2 LAST CDS_LIB standard
J 0
(-6725 3200);
DISPLAY INVISIBLE (-6725 3200);
FORCEPROP 1 LAST BODY_TYPE PLUMBING
J 0
(-6725 3250);
DISPLAY 0.872340 (-6725 3250);
PAINT GREEN (-6725 3250);
DISPLAY INVISIBLE (-6725 3250);
FORCEPROP 1 LAST HDL_TAP TRUE
J 0
(-6400 3075);
DISPLAY 0.872340 (-6400 3075);
DISPLAY INVISIBLE (-6400 3075);
FORCEPROP 1 LAST PATH I2
J 0
(-6727 3200);
DISPLAY 0.872340 (-6727 3200);
PAINT GREEN (-6727 3200);
DISPLAY INVISIBLE (-6727 3200);
FORCEADD TAP..1
(-2200 3150);
FORCEPROP 3 LASTPIN (-2250 3150) SIG_NAME P5E_CPU0_P2_RX_DP<0>
J 0
(-2240 3160);
DISPLAY 0.659574 (-2240 3160);
PAINT MONO (-2240 3160);
DISPLAY INVISIBLE (-2240 3160);
FORCEPROP 1 LASTPIN (-2250 3150) BN 0
J 0
(-2262 3158);
DISPLAY 0.680851 (-2262 3158);
PAINT GREEN (-2262 3158);
FORCEPROP 2 LAST CDS_LIB standard
J 0
(-2200 3150);
DISPLAY INVISIBLE (-2200 3150);
FORCEPROP 1 LAST BODY_TYPE PLUMBING
J 0
(-2200 3200);
DISPLAY 0.872340 (-2200 3200);
PAINT GREEN (-2200 3200);
DISPLAY INVISIBLE (-2200 3200);
FORCEPROP 1 LAST HDL_TAP TRUE
J 0
(-1875 3025);
DISPLAY 0.872340 (-1875 3025);
DISPLAY INVISIBLE (-1875 3025);
FORCEPROP 1 LAST PATH I20
J 0
(-2202 3150);
DISPLAY 0.872340 (-2202 3150);
PAINT GREEN (-2202 3150);
DISPLAY INVISIBLE (-2202 3150);
FORCEADD TAP..1
(-2200 3500);
FORCEPROP 3 LASTPIN (-2250 3500) SIG_NAME P5E_CPU0_P2_RX_DP<1>
J 0
(-2240 3510);
DISPLAY 0.659574 (-2240 3510);
PAINT MONO (-2240 3510);
DISPLAY INVISIBLE (-2240 3510);
FORCEPROP 1 LASTPIN (-2250 3500) BN 1
J 0
(-2262 3508);
DISPLAY 0.680851 (-2262 3508);
PAINT GREEN (-2262 3508);
FORCEPROP 2 LAST CDS_LIB standard
J 0
(-2200 3500);
DISPLAY INVISIBLE (-2200 3500);
FORCEPROP 1 LAST BODY_TYPE PLUMBING
J 0
(-2200 3550);
DISPLAY 0.872340 (-2200 3550);
PAINT GREEN (-2200 3550);
DISPLAY INVISIBLE (-2200 3550);
FORCEPROP 1 LAST HDL_TAP TRUE
J 0
(-1875 3375);
DISPLAY 0.872340 (-1875 3375);
DISPLAY INVISIBLE (-1875 3375);
FORCEPROP 1 LAST PATH I21
J 0
(-2202 3500);
DISPLAY 0.872340 (-2202 3500);
PAINT GREEN (-2202 3500);
DISPLAY INVISIBLE (-2202 3500);
FORCEADD TAP..1
(-2200 3850);
FORCEPROP 3 LASTPIN (-2250 3850) SIG_NAME P5E_CPU0_P2_RX_DP<2>
J 0
(-2240 3860);
DISPLAY 0.659574 (-2240 3860);
PAINT MONO (-2240 3860);
DISPLAY INVISIBLE (-2240 3860);
FORCEPROP 1 LASTPIN (-2250 3850) BN 2
J 0
(-2262 3858);
DISPLAY 0.680851 (-2262 3858);
PAINT GREEN (-2262 3858);
FORCEPROP 2 LAST CDS_LIB standard
J 0
(-2200 3850);
DISPLAY INVISIBLE (-2200 3850);
FORCEPROP 1 LAST BODY_TYPE PLUMBING
J 0
(-2200 3900);
DISPLAY 0.872340 (-2200 3900);
PAINT GREEN (-2200 3900);
DISPLAY INVISIBLE (-2200 3900);
FORCEPROP 1 LAST HDL_TAP TRUE
J 0
(-1875 3725);
DISPLAY 0.872340 (-1875 3725);
DISPLAY INVISIBLE (-1875 3725);
FORCEPROP 1 LAST PATH I22
J 0
(-2202 3850);
DISPLAY 0.872340 (-2202 3850);
PAINT GREEN (-2202 3850);
DISPLAY INVISIBLE (-2202 3850);
FORCEADD TAP..1
(-2200 4200);
FORCEPROP 3 LASTPIN (-2250 4200) SIG_NAME P5E_CPU0_P2_RX_DP<3>
J 0
(-2240 4210);
DISPLAY 0.659574 (-2240 4210);
PAINT MONO (-2240 4210);
DISPLAY INVISIBLE (-2240 4210);
FORCEPROP 1 LASTPIN (-2250 4200) BN 3
J 0
(-2262 4208);
DISPLAY 0.680851 (-2262 4208);
PAINT GREEN (-2262 4208);
FORCEPROP 2 LAST CDS_LIB standard
J 0
(-2200 4200);
DISPLAY INVISIBLE (-2200 4200);
FORCEPROP 1 LAST BODY_TYPE PLUMBING
J 0
(-2200 4250);
DISPLAY 0.872340 (-2200 4250);
PAINT GREEN (-2200 4250);
DISPLAY INVISIBLE (-2200 4250);
FORCEPROP 1 LAST HDL_TAP TRUE
J 0
(-1875 4075);
DISPLAY 0.872340 (-1875 4075);
DISPLAY INVISIBLE (-1875 4075);
FORCEPROP 1 LAST PATH I23
J 0
(-2202 4200);
DISPLAY 0.872340 (-2202 4200);
PAINT GREEN (-2202 4200);
DISPLAY INVISIBLE (-2202 4200);
FORCEADD TAP..1
(-2200 4550);
FORCEPROP 3 LASTPIN (-2250 4550) SIG_NAME P5E_CPU0_P2_RX_DP<4>
J 0
(-2240 4560);
DISPLAY 0.659574 (-2240 4560);
PAINT MONO (-2240 4560);
DISPLAY INVISIBLE (-2240 4560);
FORCEPROP 1 LASTPIN (-2250 4550) BN 4
J 0
(-2262 4558);
DISPLAY 0.680851 (-2262 4558);
PAINT GREEN (-2262 4558);
FORCEPROP 2 LAST CDS_LIB standard
J 0
(-2200 4550);
DISPLAY INVISIBLE (-2200 4550);
FORCEPROP 1 LAST BODY_TYPE PLUMBING
J 0
(-2200 4600);
DISPLAY 0.872340 (-2200 4600);
PAINT GREEN (-2200 4600);
DISPLAY INVISIBLE (-2200 4600);
FORCEPROP 1 LAST HDL_TAP TRUE
J 0
(-1875 4425);
DISPLAY 0.872340 (-1875 4425);
DISPLAY INVISIBLE (-1875 4425);
FORCEPROP 1 LAST PATH I24
J 0
(-2202 4550);
DISPLAY 0.872340 (-2202 4550);
PAINT GREEN (-2202 4550);
DISPLAY INVISIBLE (-2202 4550);
FORCEADD TAP..1
(-2000 3050);
FORCEPROP 3 LASTPIN (-2050 3050) SIG_NAME P5E_CPU0_P2_RX_DN<0>
J 0
(-2040 3060);
DISPLAY 0.659574 (-2040 3060);
PAINT MONO (-2040 3060);
DISPLAY INVISIBLE (-2040 3060);
FORCEPROP 1 LASTPIN (-2050 3050) BN 0
J 0
(-2062 3058);
DISPLAY 0.680851 (-2062 3058);
PAINT GREEN (-2062 3058);
FORCEPROP 2 LAST CDS_LIB standard
J 0
(-2000 3050);
DISPLAY INVISIBLE (-2000 3050);
FORCEPROP 1 LAST BODY_TYPE PLUMBING
J 0
(-2000 3100);
DISPLAY 0.872340 (-2000 3100);
PAINT GREEN (-2000 3100);
DISPLAY INVISIBLE (-2000 3100);
FORCEPROP 1 LAST HDL_TAP TRUE
J 0
(-1675 2925);
DISPLAY 0.872340 (-1675 2925);
DISPLAY INVISIBLE (-1675 2925);
FORCEPROP 1 LAST PATH I25
J 0
(-2002 3050);
DISPLAY 0.872340 (-2002 3050);
PAINT GREEN (-2002 3050);
DISPLAY INVISIBLE (-2002 3050);
FORCEADD TAP..1
(-2000 3400);
FORCEPROP 3 LASTPIN (-2050 3400) SIG_NAME P5E_CPU0_P2_RX_DN<1>
J 0
(-2040 3410);
DISPLAY 0.659574 (-2040 3410);
PAINT MONO (-2040 3410);
DISPLAY INVISIBLE (-2040 3410);
FORCEPROP 1 LASTPIN (-2050 3400) BN 1
J 0
(-2062 3408);
DISPLAY 0.680851 (-2062 3408);
PAINT GREEN (-2062 3408);
FORCEPROP 2 LAST CDS_LIB standard
J 0
(-2000 3400);
DISPLAY INVISIBLE (-2000 3400);
FORCEPROP 1 LAST BODY_TYPE PLUMBING
J 0
(-2000 3450);
DISPLAY 0.872340 (-2000 3450);
PAINT GREEN (-2000 3450);
DISPLAY INVISIBLE (-2000 3450);
FORCEPROP 1 LAST HDL_TAP TRUE
J 0
(-1675 3275);
DISPLAY 0.872340 (-1675 3275);
DISPLAY INVISIBLE (-1675 3275);
FORCEPROP 1 LAST PATH I26
J 0
(-2002 3400);
DISPLAY 0.872340 (-2002 3400);
PAINT GREEN (-2002 3400);
DISPLAY INVISIBLE (-2002 3400);
FORCEADD TAP..1
(-2000 3750);
FORCEPROP 3 LASTPIN (-2050 3750) SIG_NAME P5E_CPU0_P2_RX_DN<2>
J 0
(-2040 3760);
DISPLAY 0.659574 (-2040 3760);
PAINT MONO (-2040 3760);
DISPLAY INVISIBLE (-2040 3760);
FORCEPROP 1 LASTPIN (-2050 3750) BN 2
J 0
(-2062 3758);
DISPLAY 0.680851 (-2062 3758);
PAINT GREEN (-2062 3758);
FORCEPROP 2 LAST CDS_LIB standard
J 0
(-2000 3750);
DISPLAY INVISIBLE (-2000 3750);
FORCEPROP 1 LAST BODY_TYPE PLUMBING
J 0
(-2000 3800);
DISPLAY 0.872340 (-2000 3800);
PAINT GREEN (-2000 3800);
DISPLAY INVISIBLE (-2000 3800);
FORCEPROP 1 LAST HDL_TAP TRUE
J 0
(-1675 3625);
DISPLAY 0.872340 (-1675 3625);
DISPLAY INVISIBLE (-1675 3625);
FORCEPROP 1 LAST PATH I27
J 0
(-2002 3750);
DISPLAY 0.872340 (-2002 3750);
PAINT GREEN (-2002 3750);
DISPLAY INVISIBLE (-2002 3750);
FORCEADD TAP..1
(-2000 4100);
FORCEPROP 3 LASTPIN (-2050 4100) SIG_NAME P5E_CPU0_P2_RX_DN<3>
J 0
(-2040 4110);
DISPLAY 0.659574 (-2040 4110);
PAINT MONO (-2040 4110);
DISPLAY INVISIBLE (-2040 4110);
FORCEPROP 1 LASTPIN (-2050 4100) BN 3
J 0
(-2062 4108);
DISPLAY 0.680851 (-2062 4108);
PAINT GREEN (-2062 4108);
FORCEPROP 2 LAST CDS_LIB standard
J 0
(-2000 4100);
DISPLAY INVISIBLE (-2000 4100);
FORCEPROP 1 LAST BODY_TYPE PLUMBING
J 0
(-2000 4150);
DISPLAY 0.872340 (-2000 4150);
PAINT GREEN (-2000 4150);
DISPLAY INVISIBLE (-2000 4150);
FORCEPROP 1 LAST HDL_TAP TRUE
J 0
(-1675 3975);
DISPLAY 0.872340 (-1675 3975);
DISPLAY INVISIBLE (-1675 3975);
FORCEPROP 1 LAST PATH I28
J 0
(-2002 4100);
DISPLAY 0.872340 (-2002 4100);
PAINT GREEN (-2002 4100);
DISPLAY INVISIBLE (-2002 4100);
FORCEADD TAP..1
(-2000 4450);
FORCEPROP 3 LASTPIN (-2050 4450) SIG_NAME P5E_CPU0_P2_RX_DN<4>
J 0
(-2040 4460);
DISPLAY 0.659574 (-2040 4460);
PAINT MONO (-2040 4460);
DISPLAY INVISIBLE (-2040 4460);
FORCEPROP 1 LASTPIN (-2050 4450) BN 4
J 0
(-2062 4458);
DISPLAY 0.680851 (-2062 4458);
PAINT GREEN (-2062 4458);
FORCEPROP 2 LAST CDS_LIB standard
J 0
(-2000 4450);
DISPLAY INVISIBLE (-2000 4450);
FORCEPROP 1 LAST BODY_TYPE PLUMBING
J 0
(-2000 4500);
DISPLAY 0.872340 (-2000 4500);
PAINT GREEN (-2000 4500);
DISPLAY INVISIBLE (-2000 4500);
FORCEPROP 1 LAST HDL_TAP TRUE
J 0
(-1675 4325);
DISPLAY 0.872340 (-1675 4325);
DISPLAY INVISIBLE (-1675 4325);
FORCEPROP 1 LAST PATH I29
J 0
(-2002 4450);
DISPLAY 0.872340 (-2002 4450);
PAINT GREEN (-2002 4450);
DISPLAY INVISIBLE (-2002 4450);
FORCEADD TAP..1
(-6725 3550);
FORCEPROP 3 LASTPIN (-6775 3550) SIG_NAME P5E_CPU0_P2_RX_DP<9>
J 0
(-6765 3560);
DISPLAY 0.659574 (-6765 3560);
PAINT MONO (-6765 3560);
DISPLAY INVISIBLE (-6765 3560);
FORCEPROP 1 LASTPIN (-6775 3550) BN 9
J 0
(-6787 3558);
DISPLAY 0.680851 (-6787 3558);
PAINT GREEN (-6787 3558);
FORCEPROP 2 LAST CDS_LIB standard
J 0
(-6725 3550);
DISPLAY INVISIBLE (-6725 3550);
FORCEPROP 1 LAST BODY_TYPE PLUMBING
J 0
(-6725 3600);
DISPLAY 0.872340 (-6725 3600);
PAINT GREEN (-6725 3600);
DISPLAY INVISIBLE (-6725 3600);
FORCEPROP 1 LAST HDL_TAP TRUE
J 0
(-6400 3425);
DISPLAY 0.872340 (-6400 3425);
DISPLAY INVISIBLE (-6400 3425);
FORCEPROP 1 LAST PATH I3
J 0
(-6727 3550);
DISPLAY 0.872340 (-6727 3550);
PAINT GREEN (-6727 3550);
DISPLAY INVISIBLE (-6727 3550);
FORCEADD TAP..1
(-2200 4900);
FORCEPROP 3 LASTPIN (-2250 4900) SIG_NAME P5E_CPU0_P2_RX_DP<5>
J 0
(-2240 4910);
DISPLAY 0.659574 (-2240 4910);
PAINT MONO (-2240 4910);
DISPLAY INVISIBLE (-2240 4910);
FORCEPROP 1 LASTPIN (-2250 4900) BN 5
J 0
(-2262 4908);
DISPLAY 0.680851 (-2262 4908);
PAINT GREEN (-2262 4908);
FORCEPROP 2 LAST CDS_LIB standard
J 0
(-2200 4900);
DISPLAY INVISIBLE (-2200 4900);
FORCEPROP 1 LAST BODY_TYPE PLUMBING
J 0
(-2200 4950);
DISPLAY 0.872340 (-2200 4950);
PAINT GREEN (-2200 4950);
DISPLAY INVISIBLE (-2200 4950);
FORCEPROP 1 LAST HDL_TAP TRUE
J 0
(-1875 4775);
DISPLAY 0.872340 (-1875 4775);
DISPLAY INVISIBLE (-1875 4775);
FORCEPROP 1 LAST PATH I30
J 0
(-2202 4900);
DISPLAY 0.872340 (-2202 4900);
PAINT GREEN (-2202 4900);
DISPLAY INVISIBLE (-2202 4900);
FORCEADD TAP..1
(-2200 5250);
FORCEPROP 3 LASTPIN (-2250 5250) SIG_NAME P5E_CPU0_P2_RX_DP<6>
J 0
(-2240 5260);
DISPLAY 0.659574 (-2240 5260);
PAINT MONO (-2240 5260);
DISPLAY INVISIBLE (-2240 5260);
FORCEPROP 1 LASTPIN (-2250 5250) BN 6
J 0
(-2262 5258);
DISPLAY 0.680851 (-2262 5258);
PAINT GREEN (-2262 5258);
FORCEPROP 2 LAST CDS_LIB standard
J 0
(-2200 5250);
DISPLAY INVISIBLE (-2200 5250);
FORCEPROP 1 LAST BODY_TYPE PLUMBING
J 0
(-2200 5300);
DISPLAY 0.872340 (-2200 5300);
PAINT GREEN (-2200 5300);
DISPLAY INVISIBLE (-2200 5300);
FORCEPROP 1 LAST HDL_TAP TRUE
J 0
(-1875 5125);
DISPLAY 0.872340 (-1875 5125);
DISPLAY INVISIBLE (-1875 5125);
FORCEPROP 1 LAST PATH I31
J 0
(-2202 5250);
DISPLAY 0.872340 (-2202 5250);
PAINT GREEN (-2202 5250);
DISPLAY INVISIBLE (-2202 5250);
FORCEADD TAP..1
(-2200 5600);
FORCEPROP 3 LASTPIN (-2250 5600) SIG_NAME P5E_CPU0_P2_RX_DP<7>
J 0
(-2240 5610);
DISPLAY 0.659574 (-2240 5610);
PAINT MONO (-2240 5610);
DISPLAY INVISIBLE (-2240 5610);
FORCEPROP 1 LASTPIN (-2250 5600) BN 7
J 0
(-2262 5608);
DISPLAY 0.680851 (-2262 5608);
PAINT GREEN (-2262 5608);
FORCEPROP 2 LAST CDS_LIB standard
J 0
(-2200 5600);
DISPLAY INVISIBLE (-2200 5600);
FORCEPROP 1 LAST BODY_TYPE PLUMBING
J 0
(-2200 5650);
DISPLAY 0.872340 (-2200 5650);
PAINT GREEN (-2200 5650);
DISPLAY INVISIBLE (-2200 5650);
FORCEPROP 1 LAST HDL_TAP TRUE
J 0
(-1875 5475);
DISPLAY 0.872340 (-1875 5475);
DISPLAY INVISIBLE (-1875 5475);
FORCEPROP 1 LAST PATH I32
J 0
(-2202 5600);
DISPLAY 0.872340 (-2202 5600);
PAINT GREEN (-2202 5600);
DISPLAY INVISIBLE (-2202 5600);
FORCEADD TAP..1
(-2000 4800);
FORCEPROP 3 LASTPIN (-2050 4800) SIG_NAME P5E_CPU0_P2_RX_DN<5>
J 0
(-2040 4810);
DISPLAY 0.659574 (-2040 4810);
PAINT MONO (-2040 4810);
DISPLAY INVISIBLE (-2040 4810);
FORCEPROP 1 LASTPIN (-2050 4800) BN 5
J 0
(-2062 4808);
DISPLAY 0.680851 (-2062 4808);
PAINT GREEN (-2062 4808);
FORCEPROP 2 LAST CDS_LIB standard
J 0
(-2000 4800);
DISPLAY INVISIBLE (-2000 4800);
FORCEPROP 1 LAST BODY_TYPE PLUMBING
J 0
(-2000 4850);
DISPLAY 0.872340 (-2000 4850);
PAINT GREEN (-2000 4850);
DISPLAY INVISIBLE (-2000 4850);
FORCEPROP 1 LAST HDL_TAP TRUE
J 0
(-1675 4675);
DISPLAY 0.872340 (-1675 4675);
DISPLAY INVISIBLE (-1675 4675);
FORCEPROP 1 LAST PATH I33
J 0
(-2002 4800);
DISPLAY 0.872340 (-2002 4800);
PAINT GREEN (-2002 4800);
DISPLAY INVISIBLE (-2002 4800);
FORCEADD TAP..1
(-2000 5150);
FORCEPROP 3 LASTPIN (-2050 5150) SIG_NAME P5E_CPU0_P2_RX_DN<6>
J 0
(-2040 5160);
DISPLAY 0.659574 (-2040 5160);
PAINT MONO (-2040 5160);
DISPLAY INVISIBLE (-2040 5160);
FORCEPROP 1 LASTPIN (-2050 5150) BN 6
J 0
(-2062 5158);
DISPLAY 0.680851 (-2062 5158);
PAINT GREEN (-2062 5158);
FORCEPROP 2 LAST CDS_LIB standard
J 0
(-2000 5150);
DISPLAY INVISIBLE (-2000 5150);
FORCEPROP 1 LAST BODY_TYPE PLUMBING
J 0
(-2000 5200);
DISPLAY 0.872340 (-2000 5200);
PAINT GREEN (-2000 5200);
DISPLAY INVISIBLE (-2000 5200);
FORCEPROP 1 LAST HDL_TAP TRUE
J 0
(-1675 5025);
DISPLAY 0.872340 (-1675 5025);
DISPLAY INVISIBLE (-1675 5025);
FORCEPROP 1 LAST PATH I34
J 0
(-2002 5150);
DISPLAY 0.872340 (-2002 5150);
PAINT GREEN (-2002 5150);
DISPLAY INVISIBLE (-2002 5150);
FORCEADD TAP..1
(-2000 5500);
FORCEPROP 3 LASTPIN (-2050 5500) SIG_NAME P5E_CPU0_P2_RX_DN<7>
J 0
(-2040 5510);
DISPLAY 0.659574 (-2040 5510);
PAINT MONO (-2040 5510);
DISPLAY INVISIBLE (-2040 5510);
FORCEPROP 1 LASTPIN (-2050 5500) BN 7
J 0
(-2062 5508);
DISPLAY 0.680851 (-2062 5508);
PAINT GREEN (-2062 5508);
FORCEPROP 2 LAST CDS_LIB standard
J 0
(-2000 5500);
DISPLAY INVISIBLE (-2000 5500);
FORCEPROP 1 LAST BODY_TYPE PLUMBING
J 0
(-2000 5550);
DISPLAY 0.872340 (-2000 5550);
PAINT GREEN (-2000 5550);
DISPLAY INVISIBLE (-2000 5550);
FORCEPROP 1 LAST HDL_TAP TRUE
J 0
(-1675 5375);
DISPLAY 0.872340 (-1675 5375);
DISPLAY INVISIBLE (-1675 5375);
FORCEPROP 1 LAST PATH I35
J 0
(-2002 5500);
DISPLAY 0.872340 (-2002 5500);
PAINT GREEN (-2002 5500);
DISPLAY INVISIBLE (-2002 5500);
FORCEADD OFFPAGE..5
R 2
(-1000 5525);
FORCEPROP 2 LAST $XR0 25 
J 0
(-811 5525);
DISPLAY 0.638298 (-811 5525);
PAINT MONO (-811 5525);
FORCEPROP 2 LAST CDS_LIB standard
J 0
(-1000 5525);
DISPLAY INVISIBLE (-1000 5525);
FORCEPROP 1 LAST OFFPAGE TRUE
J 2
(-1325 5400);
DISPLAY 0.872340 (-1325 5400);
PAINT GREEN (-1325 5400);
DISPLAY INVISIBLE (-1325 5400);
FORCEPROP 1 LAST COMMENT_BODY TRUE
J 2
(-1100 5450);
DISPLAY 0.872340 (-1100 5450);
PAINT GREEN (-1100 5450);
DISPLAY INVISIBLE (-1100 5450);
FORCEPROP 2 LAST PATH I36
J 0
(-825 5600);
DISPLAY 0.680851 (-825 5600);
DISPLAY INVISIBLE (-825 5600);
FORCEADD OFFPAGE..5
R 2
(-1000 5625);
FORCEPROP 2 LAST $XR0 25 
J 0
(-811 5625);
DISPLAY 0.638298 (-811 5625);
PAINT MONO (-811 5625);
FORCEPROP 2 LAST CDS_LIB standard
J 0
(-1000 5625);
DISPLAY INVISIBLE (-1000 5625);
FORCEPROP 1 LAST OFFPAGE TRUE
J 2
(-1325 5500);
DISPLAY 0.872340 (-1325 5500);
PAINT GREEN (-1325 5500);
DISPLAY INVISIBLE (-1325 5500);
FORCEPROP 1 LAST COMMENT_BODY TRUE
J 2
(-1100 5550);
DISPLAY 0.872340 (-1100 5550);
PAINT GREEN (-1100 5550);
DISPLAY INVISIBLE (-1100 5550);
FORCEPROP 2 LAST PATH I37
J 0
(-825 5700);
DISPLAY 0.680851 (-825 5700);
DISPLAY INVISIBLE (-825 5700);
FORCEADD PT5161LRS..7
(-3225 4350);
FORCEPROP 1 LAST LOCATION U6012
J 0
(-3575 5975);
DISPLAY 0.723404 (-3575 5975);
PAINT GREEN (-3575 5975);
FORCEPROP 0 LAST $SEC 7
J 0
(-3575 6125);
DISPLAY 0.680851 (-3575 6125);
PAINT MONO (-3575 6125);
DISPLAY INVISIBLE (-3575 6125);
FORCEPROP 0 LAST CDS_SEC 7
J 0
(-3575 6125);
DISPLAY 0.680851 (-3575 6125);
DISPLAY INVISIBLE (-3575 6125);
FORCEPROP 0 LASTPIN (-2775 5500) $PN CK29
J 0
(-2765 5510);
DISPLAY 0.680851 (-2765 5510);
PAINT MONO (-2765 5510);
FORCEPROP 0 LASTPIN (-2775 5150) $PN CU29
J 0
(-2765 5160);
DISPLAY 0.680851 (-2765 5160);
PAINT MONO (-2765 5160);
FORCEPROP 0 LASTPIN (-2775 4800) $PN DD29
J 0
(-2765 4810);
DISPLAY 0.680851 (-2765 4810);
PAINT MONO (-2765 4810);
FORCEPROP 0 LASTPIN (-2775 4450) $PN DL29
J 0
(-2765 4460);
DISPLAY 0.680851 (-2765 4460);
PAINT MONO (-2765 4460);
FORCEPROP 0 LASTPIN (-2775 4100) $PN DV29
J 0
(-2765 4110);
DISPLAY 0.680851 (-2765 4110);
PAINT MONO (-2765 4110);
FORCEPROP 0 LASTPIN (-2775 3750) $PN EE29
J 0
(-2765 3760);
DISPLAY 0.680851 (-2765 3760);
PAINT MONO (-2765 3760);
FORCEPROP 0 LASTPIN (-2775 3400) $PN EM29
J 0
(-2765 3410);
DISPLAY 0.680851 (-2765 3410);
PAINT MONO (-2765 3410);
FORCEPROP 0 LASTPIN (-2775 3050) $PN EW29
J 0
(-2765 3060);
DISPLAY 0.680851 (-2765 3060);
PAINT MONO (-2765 3060);
FORCEPROP 0 LASTPIN (-2775 5600) $PN CH26
J 0
(-2765 5610);
DISPLAY 0.680851 (-2765 5610);
PAINT MONO (-2765 5610);
FORCEPROP 0 LASTPIN (-2775 5250) $PN CR26
J 0
(-2765 5260);
DISPLAY 0.680851 (-2765 5260);
PAINT MONO (-2765 5260);
FORCEPROP 0 LASTPIN (-2775 4900) $PN DB26
J 0
(-2765 4910);
DISPLAY 0.680851 (-2765 4910);
PAINT MONO (-2765 4910);
FORCEPROP 0 LASTPIN (-2775 4550) $PN DJ26
J 0
(-2765 4560);
DISPLAY 0.680851 (-2765 4560);
PAINT MONO (-2765 4560);
FORCEPROP 0 LASTPIN (-2775 4200) $PN DT26
J 0
(-2765 4210);
DISPLAY 0.680851 (-2765 4210);
PAINT MONO (-2765 4210);
FORCEPROP 0 LASTPIN (-2775 3850) $PN EC26
J 0
(-2765 3860);
DISPLAY 0.680851 (-2765 3860);
PAINT MONO (-2765 3860);
FORCEPROP 0 LASTPIN (-2775 3500) $PN EK26
J 0
(-2765 3510);
DISPLAY 0.680851 (-2765 3510);
PAINT MONO (-2765 3510);
FORCEPROP 0 LASTPIN (-2775 3150) $PN EU26
J 0
(-2765 3160);
DISPLAY 0.680851 (-2765 3160);
PAINT MONO (-2765 3160);
FORCEPROP 2 LAST PART_TYPE SMLF
J 0
(-3575 6075);
DISPLAY 0.680851 (-3575 6075);
FORCEPROP 2 LAST VALUE PT5161LRS
J 0
(-3575 6025);
DISPLAY 0.680851 (-3575 6025);
FORCEPROP 1 LAST MATERIAL IC
J 0
(-3575 5825);
DISPLAY 0.723404 (-3575 5825);
PAINT GREEN (-3575 5825);
FORCEPROP 2 LAST CDS_LIB pure_quanta
J 0
(-3225 4350);
DISPLAY INVISIBLE (-3225 4350);
FORCEPROP 1 LAST CDS_LMAN_SYM_OUTLINE -350,1450,300,-1400
J 0
(-3225 4350);
DISPLAY 0.468085 (-3225 4350);
PAINT GREEN (-3225 4350);
DISPLAY INVISIBLE (-3225 4350);
FORCEPROP 1 LAST NEEDS_NO_SIZE TRUE
J 0
(-3225 4350);
DISPLAY 0.723404 (-3225 4350);
PAINT GREEN (-3225 4350);
DISPLAY INVISIBLE (-3225 4350);
FORCEPROP 1 LAST PATH I38
J 0
(-3225 4350);
DISPLAY 0.723404 (-3225 4350);
PAINT GREEN (-3225 4350);
DISPLAY INVISIBLE (-3225 4350);
FORCEPROP 1 LAST PART_NUMBER AJ051610U03
J 0
(-3575 5900);
DISPLAY 0.723404 (-3575 5900);
PAINT GREEN (-3575 5900);
DISPLAY INVISIBLE (-3575 5900);
FORCEADD TAP..1
(-6525 3100);
FORCEPROP 3 LASTPIN (-6575 3100) SIG_NAME P5E_CPU0_P2_RX_DN<8>
J 0
(-6565 3110);
DISPLAY 0.659574 (-6565 3110);
PAINT MONO (-6565 3110);
DISPLAY INVISIBLE (-6565 3110);
FORCEPROP 1 LASTPIN (-6575 3100) BN 8
J 0
(-6587 3108);
DISPLAY 0.680851 (-6587 3108);
PAINT GREEN (-6587 3108);
FORCEPROP 2 LAST CDS_LIB standard
J 0
(-6525 3100);
DISPLAY INVISIBLE (-6525 3100);
FORCEPROP 1 LAST BODY_TYPE PLUMBING
J 0
(-6525 3150);
DISPLAY 0.872340 (-6525 3150);
PAINT GREEN (-6525 3150);
DISPLAY INVISIBLE (-6525 3150);
FORCEPROP 1 LAST HDL_TAP TRUE
J 0
(-6200 2975);
DISPLAY 0.872340 (-6200 2975);
DISPLAY INVISIBLE (-6200 2975);
FORCEPROP 1 LAST PATH I4
J 0
(-6527 3100);
DISPLAY 0.872340 (-6527 3100);
PAINT GREEN (-6527 3100);
DISPLAY INVISIBLE (-6527 3100);
FORCEADD TAP..1
(-6525 3450);
FORCEPROP 3 LASTPIN (-6575 3450) SIG_NAME P5E_CPU0_P2_RX_DN<9>
J 0
(-6565 3460);
DISPLAY 0.659574 (-6565 3460);
PAINT MONO (-6565 3460);
DISPLAY INVISIBLE (-6565 3460);
FORCEPROP 1 LASTPIN (-6575 3450) BN 9
J 0
(-6587 3458);
DISPLAY 0.680851 (-6587 3458);
PAINT GREEN (-6587 3458);
FORCEPROP 2 LAST CDS_LIB standard
J 0
(-6525 3450);
DISPLAY INVISIBLE (-6525 3450);
FORCEPROP 1 LAST BODY_TYPE PLUMBING
J 0
(-6525 3500);
DISPLAY 0.872340 (-6525 3500);
PAINT GREEN (-6525 3500);
DISPLAY INVISIBLE (-6525 3500);
FORCEPROP 1 LAST HDL_TAP TRUE
J 0
(-6200 3325);
DISPLAY 0.872340 (-6200 3325);
DISPLAY INVISIBLE (-6200 3325);
FORCEPROP 1 LAST PATH I5
J 0
(-6527 3450);
DISPLAY 0.872340 (-6527 3450);
PAINT GREEN (-6527 3450);
DISPLAY INVISIBLE (-6527 3450);
FORCEADD TAP..1
(-6725 3900);
FORCEPROP 3 LASTPIN (-6775 3900) SIG_NAME P5E_CPU0_P2_RX_DP<10>
J 0
(-6765 3910);
DISPLAY 0.659574 (-6765 3910);
PAINT MONO (-6765 3910);
DISPLAY INVISIBLE (-6765 3910);
FORCEPROP 1 LASTPIN (-6775 3900) BN 10
J 0
(-6787 3908);
DISPLAY 0.680851 (-6787 3908);
PAINT GREEN (-6787 3908);
FORCEPROP 2 LAST CDS_LIB standard
J 0
(-6725 3900);
DISPLAY INVISIBLE (-6725 3900);
FORCEPROP 1 LAST BODY_TYPE PLUMBING
J 0
(-6725 3950);
DISPLAY 0.872340 (-6725 3950);
PAINT GREEN (-6725 3950);
DISPLAY INVISIBLE (-6725 3950);
FORCEPROP 1 LAST HDL_TAP TRUE
J 0
(-6400 3775);
DISPLAY 0.872340 (-6400 3775);
DISPLAY INVISIBLE (-6400 3775);
FORCEPROP 1 LAST PATH I6
J 0
(-6727 3900);
DISPLAY 0.872340 (-6727 3900);
PAINT GREEN (-6727 3900);
DISPLAY INVISIBLE (-6727 3900);
FORCEADD TAP..1
(-6725 4250);
FORCEPROP 3 LASTPIN (-6775 4250) SIG_NAME P5E_CPU0_P2_RX_DP<11>
J 0
(-6765 4260);
DISPLAY 0.659574 (-6765 4260);
PAINT MONO (-6765 4260);
DISPLAY INVISIBLE (-6765 4260);
FORCEPROP 1 LASTPIN (-6775 4250) BN 11
J 0
(-6787 4258);
DISPLAY 0.680851 (-6787 4258);
PAINT GREEN (-6787 4258);
FORCEPROP 2 LAST CDS_LIB standard
J 0
(-6725 4250);
DISPLAY INVISIBLE (-6725 4250);
FORCEPROP 1 LAST BODY_TYPE PLUMBING
J 0
(-6725 4300);
DISPLAY 0.872340 (-6725 4300);
PAINT GREEN (-6725 4300);
DISPLAY INVISIBLE (-6725 4300);
FORCEPROP 1 LAST HDL_TAP TRUE
J 0
(-6400 4125);
DISPLAY 0.872340 (-6400 4125);
DISPLAY INVISIBLE (-6400 4125);
FORCEPROP 1 LAST PATH I7
J 0
(-6727 4250);
DISPLAY 0.872340 (-6727 4250);
PAINT GREEN (-6727 4250);
DISPLAY INVISIBLE (-6727 4250);
FORCEADD TAP..1
(-6725 4600);
FORCEPROP 3 LASTPIN (-6775 4600) SIG_NAME P5E_CPU0_P2_RX_DP<12>
J 0
(-6765 4610);
DISPLAY 0.659574 (-6765 4610);
PAINT MONO (-6765 4610);
DISPLAY INVISIBLE (-6765 4610);
FORCEPROP 1 LASTPIN (-6775 4600) BN 12
J 0
(-6787 4608);
DISPLAY 0.680851 (-6787 4608);
PAINT GREEN (-6787 4608);
FORCEPROP 2 LAST CDS_LIB standard
J 0
(-6725 4600);
DISPLAY INVISIBLE (-6725 4600);
FORCEPROP 1 LAST BODY_TYPE PLUMBING
J 0
(-6725 4650);
DISPLAY 0.872340 (-6725 4650);
PAINT GREEN (-6725 4650);
DISPLAY INVISIBLE (-6725 4650);
FORCEPROP 1 LAST HDL_TAP TRUE
J 0
(-6400 4475);
DISPLAY 0.872340 (-6400 4475);
DISPLAY INVISIBLE (-6400 4475);
FORCEPROP 1 LAST PATH I8
J 0
(-6727 4600);
DISPLAY 0.872340 (-6727 4600);
PAINT GREEN (-6727 4600);
DISPLAY INVISIBLE (-6727 4600);
FORCEADD TAP..1
(-6525 3800);
FORCEPROP 3 LASTPIN (-6575 3800) SIG_NAME P5E_CPU0_P2_RX_DN<10>
J 0
(-6565 3810);
DISPLAY 0.659574 (-6565 3810);
PAINT MONO (-6565 3810);
DISPLAY INVISIBLE (-6565 3810);
FORCEPROP 1 LASTPIN (-6575 3800) BN 10
J 0
(-6587 3808);
DISPLAY 0.680851 (-6587 3808);
PAINT GREEN (-6587 3808);
FORCEPROP 2 LAST CDS_LIB standard
J 0
(-6525 3800);
DISPLAY INVISIBLE (-6525 3800);
FORCEPROP 1 LAST BODY_TYPE PLUMBING
J 0
(-6525 3850);
DISPLAY 0.872340 (-6525 3850);
PAINT GREEN (-6525 3850);
DISPLAY INVISIBLE (-6525 3850);
FORCEPROP 1 LAST HDL_TAP TRUE
J 0
(-6200 3675);
DISPLAY 0.872340 (-6200 3675);
DISPLAY INVISIBLE (-6200 3675);
FORCEPROP 1 LAST PATH I9
J 0
(-6527 3800);
DISPLAY 0.872340 (-6527 3800);
PAINT GREEN (-6527 3800);
DISPLAY INVISIBLE (-6527 3800);
FORCEADD QUANTA_TITLE_BLOCK_C..1
(0 0);
FORCEPROP 0 LAST CDS_CON_LAST_MODIFIED Thu Sep 14 16:12:52 2023
J 0
(-1885 15);
DISPLAY INVISIBLE (-1885 15);
FORCEPROP 1 LAST CUSTOM_TXT_CDS <CON_LAST_MODIFIED>
J 0
(-1885 15);
DISPLAY 0.978723 (-1885 15);
FORCEPROP 2 LAST CUSTOM_TXT_CDS <XR_PAGE_TITLE>
J 0
(-7890 5250);
DISPLAY 0.638298 (-7890 5250);
PAINT PINK (-7890 5250);
DISPLAY INVISIBLE (-7890 5250);
FORCEPROP 1 LAST CUSTOM_TXT_CDS <NAME_2>
J 0
(-3175 50);
FORCEPROP 1 LAST CUSTOM_TXT_CDS <NAME_1>
J 0
(-3175 175);
FORCEPROP 1 LAST CUSTOM_TXT_CDS <Q_NUMBER>
J 0
(-1403 103);
DISPLAY 1.212766 (-1403 103);
FORCEPROP 1 LAST CUSTOM_TXT_CDS <Q_PROJ>
J 0
(-2382 102);
DISPLAY 1.212766 (-2382 102);
FORCEPROP 1 LAST CUSTOM_TXT_CDS <Q_REV>
J 0
(-184 103);
DISPLAY 1.212766 (-184 103);
FORCEPROP 1 LAST CUSTOM_TXT_CDS <CON_PAGE_NUM> OF <CON_TOTAL_PAGES>
J 0
(-446 18);
DISPLAY 0.978723 (-446 18);
FORCEPROP 1 LAST Q_TITLE RETIMER_CPU0_P2(2)
J 0
(-9366 26);
DISPLAY 2.446809 (-9366 26);
PAINT GREEN (-9366 26);
FORCEPROP 2 LAST CDS_LIB pure_quanta
J 0
(0 0);
DISPLAY INVISIBLE (0 0);
FORCEPROP 1 LAST CDS_LMAN_SYM_OUTLINE -9475,6775,100,-125
J 0
(0 0);
DISPLAY 0.468085 (0 0);
PAINT GREEN (0 0);
DISPLAY INVISIBLE (0 0);
FORCEPROP 2 LAST PAGE_BORDER TRUE
J 0
(-7890 5250);
DISPLAY 0.638298 (-7890 5250);
PAINT PINK (-7890 5250);
DISPLAY INVISIBLE (-7890 5250);
FORCEPROP 2 LAST CDS_XR_PAGE_TITLE CR-296 : @T6G_MB_LIB.T6G(SCH_1):PAGE296
J 0
(-7890 5250);
DISPLAY 0.638298 (-7890 5250);
PAINT PINK (-7890 5250);
DISPLAY INVISIBLE (-7890 5250);
FORCEPROP 1 LAST Q_DEPT BU9
J 1
(-3763 49);
DISPLAY 1.957447 (-3763 49);
PAINT GREEN (-3763 49);
DISPLAY INVISIBLE (-3763 49);
FORCEPROP 1 LAST COMMENT_BODY TRUE
J 0
(12 -13);
DISPLAY 0.978723 (12 -13);
PAINT GREEN (12 -13);
DISPLAY INVISIBLE (12 -13);
WIRE 17 -1 (-6675 3925)(-6675 3575);
WIRE 17 -1 (-6675 4275)(-6675 3925);
WIRE 17 -1 (-6675 3575)(-6675 3225);
WIRE 17 -1 (-6675 4275)(-6675 4625);
WIRE 17 -1 (-6675 4975)(-6675 4625);
WIRE 17 -1 (-6675 5325)(-6675 4975);
WIRE 17 -1 (-6675 5675)(-6675 5325);
WIRE 17 -1 (-6675 5900)(-6675 5675);
WIRE 17 -1 (-6675 5900)(-5550 5900);
FORCEPROP 2 LAST SIG_NAME P5E_CPU0_P2_RX_DP<15:8>
J 0
(-6410 5910);
DISPLAY 0.680851 (-6410 5910);
PAINT WHITE (-6410 5910);
WIRE 17 -1 (-2150 5625)(-2150 5275);
WIRE 17 -1 (-2150 5625)(-1050 5625);
FORCEPROP 2 LAST SIG_NAME P5E_CPU0_P2_RX_DP<7:0>
J 0
(-1885 5635);
DISPLAY 0.680851 (-1885 5635);
PAINT WHITE (-1885 5635);
WIRE 17 -1 (-2150 3525)(-2150 3175);
WIRE 17 -1 (-2150 3875)(-2150 3525);
WIRE 17 -1 (-2150 4225)(-2150 3875);
WIRE 17 -1 (-2150 4225)(-2150 4575);
WIRE 17 -1 (-2150 4925)(-2150 4575);
WIRE 17 -1 (-2150 5275)(-2150 4925);
WIRE 17 -1 (-6475 3825)(-6475 3475);
WIRE 17 -1 (-6475 4175)(-6475 3825);
WIRE 17 -1 (-6475 3475)(-6475 3125);
WIRE 17 -1 (-6475 4175)(-6475 4525);
WIRE 17 -1 (-6475 4875)(-6475 4525);
WIRE 17 -1 (-6475 5225)(-6475 4875);
WIRE 17 -1 (-6475 5575)(-6475 5225);
WIRE 17 -1 (-6475 5800)(-6475 5575);
WIRE 17 -1 (-6475 5800)(-5575 5800);
FORCEPROP 2 LAST SIG_NAME P5E_CPU0_P2_RX_DN<15:8>
J 0
(-6410 5810);
DISPLAY 0.680851 (-6410 5810);
PAINT WHITE (-6410 5810);
WIRE 17 -1 (-1950 5525)(-1050 5525);
FORCEPROP 2 LAST SIG_NAME P5E_CPU0_P2_RX_DN<7:0>
J 0
(-1885 5535);
DISPLAY 0.680851 (-1885 5535);
PAINT WHITE (-1885 5535);
WIRE 17 -1 (-1950 4125)(-1950 4475);
WIRE 17 -1 (-1950 4125)(-1950 3775);
WIRE 17 -1 (-1950 4825)(-1950 4475);
WIRE 17 -1 (-1950 5175)(-1950 4825);
WIRE 17 -1 (-1950 3775)(-1950 3425);
WIRE 17 -1 (-1950 3425)(-1950 3075);
WIRE 17 -1 (-1950 5525)(-1950 5175);
WIRE 16 -1 (-7300 5650)(-6775 5650);
WIRE 16 -1 (-7300 5550)(-6575 5550);
WIRE 16 -1 (-7300 5300)(-6775 5300);
WIRE 16 -1 (-7300 5200)(-6575 5200);
WIRE 16 -1 (-2775 3850)(-2250 3850);
WIRE 16 -1 (-2775 5150)(-2050 5150);
WIRE 16 -1 (-2775 3750)(-2050 3750);
WIRE 16 -1 (-2775 4800)(-2050 4800);
WIRE 16 -1 (-2775 4450)(-2050 4450);
WIRE 16 -1 (-2775 3400)(-2050 3400);
WIRE 16 -1 (-2775 3050)(-2050 3050);
WIRE 16 -1 (-2775 4100)(-2050 4100);
WIRE 16 -1 (-2775 5500)(-2050 5500);
WIRE 16 -1 (-7300 4500)(-6575 4500);
WIRE 16 -1 (-7300 4150)(-6575 4150);
WIRE 16 -1 (-7300 3100)(-6575 3100);
WIRE 16 -1 (-7300 4850)(-6575 4850);
WIRE 16 -1 (-7300 3800)(-6575 3800);
WIRE 16 -1 (-7300 3450)(-6575 3450);
WIRE 16 -1 (-2775 4550)(-2250 4550);
WIRE 16 -1 (-2775 4900)(-2250 4900);
WIRE 16 -1 (-7300 4950)(-6775 4950);
WIRE 16 -1 (-7300 3900)(-6775 3900);
WIRE 16 -1 (-2775 4200)(-2250 4200);
WIRE 16 -1 (-2775 3500)(-2250 3500);
WIRE 16 -1 (-2775 3150)(-2250 3150);
WIRE 16 -1 (-2775 5600)(-2250 5600);
WIRE 16 -1 (-2775 5250)(-2250 5250);
WIRE 16 -1 (-7300 3200)(-6775 3200);
WIRE 16 -1 (-7300 4250)(-6775 4250);
WIRE 16 -1 (-7300 4600)(-6775 4600);
WIRE 16 -1 (-7300 3550)(-6775 3550);
FORCENOTE
P5E_CPU0_P2_RX_DP/DN<0-15> LANE REVERSAL
(-8925 6300) 0;
DISPLAY LEFT (-8925 6300);
DISPLAY 2.000000 (-8925 6300);
FORCENOTE
RETIMER TO CPU
(-8100 2650) 0;
DISPLAY LEFT (-8100 2650);
DISPLAY 3.148936 (-8100 2650);
FORCENOTE
RETIMER TO CPU
(-3650 2575) 0;
DISPLAY LEFT (-3650 2575);
DISPLAY 3.148936 (-3650 2575);
QUIT
